# S9S_MB_2U (Grand Teton) — schematic netlist excerpt (pin names and nets, part order shuffled) for the footprints in the layout excerpt that follows; sources: Cadence DE-HDL packaged netlist, KiCad conversion of 03242023_DA0F0TMBIJ0_F0T_Motherboard_J_brd_V01_OCP.brd

C811  Q_CAP_DIFFBUS  DIFF BUS_0.22UF 6.3V 20% X6S  pkg C0201  page 175 : \1\ = P5E_CPU1_PE1_TX_C_DP<13> ; \2\ = P5E_CPU1_PE1_TX_DP<13>
R3933  Q_RES  16.9K 1% CHIP  pkg 0402LF  page 301 : A = P12V_AUX ; B = MB0_P12V_STBY_PWRGD
R4719  Q_RES  10K 1% CHIP  pkg 0402LF  page 224 : A = P3V3_AUX ; B = FM_AC_PWR_BTN_PLD_ISO_N

(kicad_pcb
	(version 20260206)
	(generator "pcbnew")
	(generator_version "10.0")
	(general
		(thickness 1.6)
		(legacy_teardrops no)
	)
	(paper "A4")
	(title_block
		(title "03242023_DA0F0TMBIJ0_F0T_Motherboard_J_brd_V01_OCP.brd")
		(comment 1 "Grand Teton / footprints 2862-2864 of 6105")
	)
	(layers
		(0 "F.Cu" signal "TOP")
		(4 "In1.Cu" signal "GND")
		(6 "In2.Cu" signal "IN1")
		(8 "In3.Cu" signal "GND1")
		(10 "In4.Cu" signal "IN2")
		(12 "In5.Cu" signal "GND2")
		(14 "In6.Cu" signal "IN3")
		(16 "In7.Cu" signal "GND3")
		(18 "In8.Cu" signal "VCC")
		(20 "In9.Cu" signal "VCC1")
		(22 "In10.Cu" signal "GND4")
		(24 "In11.Cu" signal "IN4")
		(26 "In12.Cu" signal "GND5")
		(28 "In13.Cu" signal "IN5")
		(30 "In14.Cu" signal "GND6")
		(32 "In15.Cu" signal "IN6")
		(34 "In16.Cu" signal "GND7")
		(2 "B.Cu" signal "BOTTOM")
		(9 "F.Adhes" user "F.Adhesive")
		(11 "B.Adhes" user "B.Adhesive")
		(13 "F.Paste" user "Package Geometry/Pastemask Top")
		(15 "B.Paste" user "Package Geometry/Pastemask Bottom")
		(5 "F.SilkS" user "Ref Des/Silkscreen Top")
		(7 "B.SilkS" user "Ref Des/Silkscreen Bottom")
		(1 "F.Mask" user "Board Geometry/Soldermask Top")
		(3 "B.Mask" user "Board Geometry/Soldermask Bottom")
		(17 "Dwgs.User" user "User.Drawings")
		(19 "Cmts.User" user "User.Comments")
		(21 "Eco1.User" user "User.Eco1")
		(23 "Eco2.User" user "User.Eco2")
		(25 "Edge.Cuts" user "Board Geometry/Outline")
		(27 "Margin" user)
		(31 "F.CrtYd" user "Package Geometry/Place Bound Top")
		(29 "B.CrtYd" user "Package Geometry/Place Bound Bottom")
		(35 "F.Fab" user "Ref Des/Assembly Top")
		(33 "B.Fab" user "Ref Des/Assembly Bottom")
	)
	(footprint ""
		(layer "F.Cu")
		(at 208.49336 -119.1006 180)
		(property "Reference" "R4719"
			(at 0 0 180)
			(layer "F.SilkS")
			(hide yes)
			(effects
				(font
					(size 1.27 1.27)
				)
			)
		)
		(property "Value" ""
			(at 0 0 180)
			(layer "F.Fab")
			(effects
				(font
					(size 1.27 1.27)
				)
			)
		)
		(duplicate_pad_numbers_are_jumpers no)
		(fp_line
			(start 0.7874 0.4064)
			(end -0.7874 0.4064)
			(stroke
				(width 0.1524)
				(type default)
			)
			(layer "F.SilkS")
		)
		(fp_line
			(start 0.7874 -0.4064)
			(end 0.7874 0.4064)
			(stroke
				(width 0.1524)
				(type default)
			)
			(layer "F.SilkS")
		)
		(fp_line
			(start -0.7874 0.4064)
			(end -0.7874 -0.4064)
			(stroke
				(width 0.1524)
				(type default)
			)
			(layer "F.SilkS")
		)
		(fp_line
			(start -0.7874 -0.4064)
			(end 0.7874 -0.4064)
			(stroke
				(width 0.1524)
				(type default)
			)
			(layer "F.SilkS")
		)
		(fp_line
			(start 0.67945 0.3048)
			(end 0.120396 0.3048)
			(stroke
				(width 0.1)
				(type default)
			)
			(layer "F.Fab")
		)
		(fp_line
			(start 0.67945 -0.3048)
			(end 0.67945 0.3048)
			(stroke
				(width 0.1)
				(type default)
			)
			(layer "F.Fab")
		)
		(fp_line
			(start 0.12065 -0.2794)
			(end 0.12065 -0.3048)
			(stroke
				(width 0.1)
				(type default)
			)
			(layer "F.Fab")
		)
		(fp_line
			(start 0.12065 -0.3048)
			(end 0.67945 -0.3048)
			(stroke
				(width 0.1)
				(type default)
			)
			(layer "F.Fab")
		)
		(fp_line
			(start 0.120396 0.3048)
			(end 0.120396 0.2794)
			(stroke
				(width 0.1)
				(type default)
			)
			(layer "F.Fab")
		)
		(fp_line
			(start 0.120396 0.2794)
			(end -0.12065 0.2794)
			(stroke
				(width 0.1)
				(type default)
			)
			(layer "F.Fab")
		)
		(fp_line
			(start -0.12065 0.3048)
			(end -0.67945 0.3048)
			(stroke
				(width 0.1)
				(type default)
			)
			(layer "F.Fab")
		)
		(fp_line
			(start -0.12065 0.2794)
			(end -0.12065 0.3048)
			(stroke
				(width 0.1)
				(type default)
			)
			(layer "F.Fab")
		)
		(fp_line
			(start -0.12065 -0.2794)
			(end 0.12065 -0.2794)
			(stroke
				(width 0.1)
				(type default)
			)
			(layer "F.Fab")
		)
		(fp_line
			(start -0.12065 -0.305054)
			(end -0.12065 -0.2794)
			(stroke
				(width 0.1)
				(type default)
			)
			(layer "F.Fab")
		)
		(fp_line
			(start -0.67945 0.3048)
			(end -0.67945 -0.305054)
			(stroke
				(width 0.1)
				(type default)
			)
			(layer "F.Fab")
		)
		(fp_line
			(start -0.67945 -0.305054)
			(end -0.12065 -0.305054)
			(stroke
				(width 0.1)
				(type default)
			)
			(layer "F.Fab")
		)
		(pad "1" smd circle
			(at -0.40005 0 180)
			(size 0 0)
			(layers "F.Cu" "F.Mask" "F.Paste")
			(net "P3V3_AUX")
		)
		(pad "2" smd circle
			(at 0.40005 0 180)
			(size 0 0)
			(layers "F.Cu" "F.Mask" "F.Paste")
			(net "FM_AC_PWR_BTN_PLD_ISO_N")
		)
	)
	(footprint ""
		(layer "F.Cu")
		(at 21.096478 -16.099536 90)
		(property "Reference" "C811"
			(at 0 0 90)
			(layer "F.SilkS")
			(hide yes)
			(effects
				(font
					(size 1.27 1.27)
				)
			)
		)
		(property "Value" ""
			(at 0 0 90)
			(layer "F.Fab")
			(effects
				(font
					(size 1.27 1.27)
				)
			)
		)
		(duplicate_pad_numbers_are_jumpers no)
		(fp_line
			(start 0.299974 -0.150114)
			(end 0.299974 0.150114)
			(stroke
				(width 0.1)
				(type default)
			)
			(layer "F.Fab")
		)
		(fp_line
			(start -0.299974 -0.150114)
			(end 0.299974 -0.150114)
			(stroke
				(width 0.1)
				(type default)
			)
			(layer "F.Fab")
		)
		(fp_line
			(start 0.299974 0.150114)
			(end -0.299974 0.150114)
			(stroke
				(width 0.1)
				(type default)
			)
			(layer "F.Fab")
		)
		(fp_line
			(start -0.299974 0.150114)
			(end -0.299974 -0.150114)
			(stroke
				(width 0.1)
				(type default)
			)
			(layer "F.Fab")
		)
		(pad "1" smd rect
			(at -0.2667 0 90)
			(size 0.3048 0.381)
			(layers "F.Cu" "F.Mask" "F.Paste")
			(net "P5E_CPU1_PE1_TX_C_DP<13>")
		)
		(pad "2" smd rect
			(at 0.2667 0 90)
			(size 0.3048 0.381)
			(layers "F.Cu" "F.Mask" "F.Paste")
			(net "P5E_CPU1_PE1_TX_DP<13>")
		)
	)
	(footprint ""
		(layer "F.Cu")
		(at 179.342288 -406.898602)
		(property "Reference" "R3933"
			(at 0 0 0)
			(layer "F.SilkS")
			(hide yes)
			(effects
				(font
					(size 1.27 1.27)
				)
			)
		)
		(property "Value" ""
			(at 0 0 0)
			(layer "F.Fab")
			(effects
				(font
					(size 1.27 1.27)
				)
			)
		)
		(duplicate_pad_numbers_are_jumpers no)
		(fp_line
			(start -0.7874 -0.4064)
			(end 0.7874 -0.4064)
			(stroke
				(width 0.1524)
				(type default)
			)
			(layer "F.SilkS")
		)
		(fp_line
			(start -0.7874 0.4064)
			(end -0.7874 -0.4064)
			(stroke
				(width 0.1524)
				(type default)
			)
			(layer "F.SilkS")
		)
		(fp_line
			(start 0.7874 -0.4064)
			(end 0.7874 0.4064)
			(stroke
				(width 0.1524)
				(type default)
			)
			(layer "F.SilkS")
		)
		(fp_line
			(start 0.7874 0.4064)
			(end -0.7874 0.4064)
			(stroke
				(width 0.1524)
				(type default)
			)
			(layer "F.SilkS")
		)
		(fp_line
			(start -0.67945 -0.305054)
			(end -0.12065 -0.305054)
			(stroke
				(width 0.1)
				(type default)
			)
			(layer "F.Fab")
		)
		(fp_line
			(start -0.67945 0.3048)
			(end -0.67945 -0.305054)
			(stroke
				(width 0.1)
				(type default)
			)
			(layer "F.Fab")
		)
		(fp_line
			(start -0.12065 -0.305054)
			(end -0.12065 -0.2794)
			(stroke
				(width 0.1)
				(type default)
			)
			(layer "F.Fab")
		)
		(fp_line
			(start -0.12065 -0.2794)
			(end 0.12065 -0.2794)
			(stroke
				(width 0.1)
				(type default)
			)
			(layer "F.Fab")
		)
		(fp_line
			(start -0.12065 0.2794)
			(end -0.12065 0.3048)
			(stroke
				(width 0.1)
				(type default)
			)
			(layer "F.Fab")
		)
		(fp_line
			(start -0.12065 0.3048)
			(end -0.67945 0.3048)
			(stroke
				(width 0.1)
				(type default)
			)
			(layer "F.Fab")
		)
		(fp_line
			(start 0.120396 0.2794)
			(end -0.12065 0.2794)
			(stroke
				(width 0.1)
				(type default)
			)
			(layer "F.Fab")
		)
		(fp_line
			(start 0.120396 0.3048)
			(end 0.120396 0.2794)
			(stroke
				(width 0.1)
				(type default)
			)
			(layer "F.Fab")
		)
		(fp_line
			(start 0.12065 -0.3048)
			(end 0.67945 -0.3048)
			(stroke
				(width 0.1)
				(type default)
			)
			(layer "F.Fab")
		)
		(fp_line
			(start 0.12065 -0.2794)
			(end 0.12065 -0.3048)
			(stroke
				(width 0.1)
				(type default)
			)
			(layer "F.Fab")
		)
		(fp_line
			(start 0.67945 -0.3048)
			(end 0.67945 0.3048)
			(stroke
				(width 0.1)
				(type default)
			)
			(layer "F.Fab")
		)
		(fp_line
			(start 0.67945 0.3048)
			(end 0.120396 0.3048)
			(stroke
				(width 0.1)
				(type default)
			)
			(layer "F.Fab")
		)
		(pad "1" smd circle
			(at -0.40005 0)
			(size 0 0)
			(layers "F.Cu" "F.Mask" "F.Paste")
			(net "P12V_AUX")
		)
		(pad "2" smd circle
			(at 0.40005 0)
			(size 0 0)
			(layers "F.Cu" "F.Mask" "F.Paste")
			(net "MB0_P12V_STBY_PWRGD")
		)
	)
)
